# SCM (Grand Teton) — schematic netlist excerpt (pin names and nets, part order shuffled) for the footprints in the layout excerpt that follows; sources: Cadence DE-HDL packaged netlist, KiCad conversion of 12092022_DA0F0TMDCD0_F0T_Management_Board_D_brd_V3_OCP.brd

R511  Q_RES  33.2 1% CHIP  pkg 0402LF  page 32 : A = JTAG_SCM_TMS ; B = JTAG_SCM_PLD_TMS
R335  Q_RES  120 1% CHIP  pkg 0402LF  page 20 : A = GND ; B = M_BMC_DDR4_MA<9>

(kicad_pcb
	(version 20260206)
	(generator "pcbnew")
	(generator_version "10.0")
	(general
		(thickness 1.6)
		(legacy_teardrops no)
	)
	(paper "A4")
	(title_block
		(title "12092022_DA0F0TMDCD0_F0T_Management_Board_D_brd_V3_OCP.brd")
		(comment 1 "Grand Teton / footprints 400-401 of 1440")
	)
	(layers
		(0 "F.Cu" signal "TOP")
		(4 "In1.Cu" signal "GND")
		(6 "In2.Cu" signal "IN1")
		(8 "In3.Cu" signal "GND1")
		(10 "In4.Cu" signal "IN2")
		(12 "In5.Cu" signal "VCC")
		(14 "In6.Cu" signal "VCC1")
		(16 "In7.Cu" signal "IN3")
		(18 "In8.Cu" signal "GND2")
		(20 "In9.Cu" signal "IN4")
		(22 "In10.Cu" signal "GND3")
		(2 "B.Cu" signal "BOTTOM")
		(9 "F.Adhes" user "F.Adhesive")
		(11 "B.Adhes" user "B.Adhesive")
		(13 "F.Paste" user "Package Geometry/Pastemask Top")
		(15 "B.Paste" user "Package Geometry/Pastemask Bottom")
		(5 "F.SilkS" user "Ref Des/Silkscreen Top")
		(7 "B.SilkS" user "Ref Des/Silkscreen Bottom")
		(1 "F.Mask" user "Board Geometry/Soldermask Top")
		(3 "B.Mask" user "Board Geometry/Soldermask Bottom")
		(17 "Dwgs.User" user "User.Drawings")
		(19 "Cmts.User" user "User.Comments")
		(21 "Eco1.User" user "User.Eco1")
		(23 "Eco2.User" user "User.Eco2")
		(25 "Edge.Cuts" user "Board Geometry/Outline")
		(27 "Margin" user)
		(31 "F.CrtYd" user "Package Geometry/Place Bound Top")
		(29 "B.CrtYd" user "Package Geometry/Place Bound Bottom")
		(35 "F.Fab" user "Ref Des/Assembly Top")
		(33 "B.Fab" user "Ref Des/Assembly Bottom")
	)
	(footprint ""
		(layer "F.Cu")
		(at 85.29955 -43.157394 180)
		(property "Reference" "R335"
			(at 0 0 180)
			(layer "F.SilkS")
			(hide yes)
			(effects
				(font
					(size 1.27 1.27)
				)
			)
		)
		(property "Value" ""
			(at 0 0 180)
			(layer "F.Fab")
			(effects
				(font
					(size 1.27 1.27)
				)
			)
		)
		(duplicate_pad_numbers_are_jumpers no)
		(fp_line
			(start 0.7874 0.4064)
			(end -0.7874 0.4064)
			(stroke
				(width 0.1524)
				(type default)
			)
			(layer "F.SilkS")
		)
		(fp_line
			(start 0.7874 -0.4064)
			(end 0.7874 0.4064)
			(stroke
				(width 0.1524)
				(type default)
			)
			(layer "F.SilkS")
		)
		(fp_line
			(start -0.7874 0.4064)
			(end -0.7874 -0.4064)
			(stroke
				(width 0.1524)
				(type default)
			)
			(layer "F.SilkS")
		)
		(fp_line
			(start -0.7874 -0.4064)
			(end 0.7874 -0.4064)
			(stroke
				(width 0.1524)
				(type default)
			)
			(layer "F.SilkS")
		)
		(fp_line
			(start 0.67945 0.3048)
			(end 0.120396 0.3048)
			(stroke
				(width 0.1)
				(type default)
			)
			(layer "F.Fab")
		)
		(fp_line
			(start 0.67945 -0.3048)
			(end 0.67945 0.3048)
			(stroke
				(width 0.1)
				(type default)
			)
			(layer "F.Fab")
		)
		(fp_line
			(start 0.12065 -0.2794)
			(end 0.12065 -0.3048)
			(stroke
				(width 0.1)
				(type default)
			)
			(layer "F.Fab")
		)
		(fp_line
			(start 0.12065 -0.3048)
			(end 0.67945 -0.3048)
			(stroke
				(width 0.1)
				(type default)
			)
			(layer "F.Fab")
		)
		(fp_line
			(start 0.120396 0.3048)
			(end 0.120396 0.2794)
			(stroke
				(width 0.1)
				(type default)
			)
			(layer "F.Fab")
		)
		(fp_line
			(start 0.120396 0.2794)
			(end -0.12065 0.2794)
			(stroke
				(width 0.1)
				(type default)
			)
			(layer "F.Fab")
		)
		(fp_line
			(start -0.12065 0.3048)
			(end -0.67945 0.3048)
			(stroke
				(width 0.1)
				(type default)
			)
			(layer "F.Fab")
		)
		(fp_line
			(start -0.12065 0.2794)
			(end -0.12065 0.3048)
			(stroke
				(width 0.1)
				(type default)
			)
			(layer "F.Fab")
		)
		(fp_line
			(start -0.12065 -0.2794)
			(end 0.12065 -0.2794)
			(stroke
				(width 0.1)
				(type default)
			)
			(layer "F.Fab")
		)
		(fp_line
			(start -0.12065 -0.305054)
			(end -0.12065 -0.2794)
			(stroke
				(width 0.1)
				(type default)
			)
			(layer "F.Fab")
		)
		(fp_line
			(start -0.67945 0.3048)
			(end -0.67945 -0.305054)
			(stroke
				(width 0.1)
				(type default)
			)
			(layer "F.Fab")
		)
		(fp_line
			(start -0.67945 -0.305054)
			(end -0.12065 -0.305054)
			(stroke
				(width 0.1)
				(type default)
			)
			(layer "F.Fab")
		)
		(pad "1" smd circle
			(at -0.40005 0 180)
			(size 0 0)
			(layers "F.Cu" "F.Mask" "F.Paste")
			(net "GND")
		)
		(pad "2" smd circle
			(at 0.40005 0 180)
			(size 0 0)
			(layers "F.Cu" "F.Mask" "F.Paste")
			(net "M_BMC_DDR4_MA<9>")
		)
	)
	(footprint ""
		(layer "F.Cu")
		(at 64.9732 -24.1554 180)
		(property "Reference" "R511"
			(at 0 0 180)
			(layer "F.SilkS")
			(hide yes)
			(effects
				(font
					(size 1.27 1.27)
				)
			)
		)
		(property "Value" ""
			(at 0 0 180)
			(layer "F.Fab")
			(effects
				(font
					(size 1.27 1.27)
				)
			)
		)
		(duplicate_pad_numbers_are_jumpers no)
		(fp_line
			(start 0.7874 0.4064)
			(end -0.7874 0.4064)
			(stroke
				(width 0.1524)
				(type default)
			)
			(layer "F.SilkS")
		)
		(fp_line
			(start 0.7874 -0.4064)
			(end 0.7874 0.4064)
			(stroke
				(width 0.1524)
				(type default)
			)
			(layer "F.SilkS")
		)
		(fp_line
			(start -0.7874 0.4064)
			(end -0.7874 -0.4064)
			(stroke
				(width 0.1524)
				(type default)
			)
			(layer "F.SilkS")
		)
		(fp_line
			(start -0.7874 -0.4064)
			(end 0.7874 -0.4064)
			(stroke
				(width 0.1524)
				(type default)
			)
			(layer "F.SilkS")
		)
		(fp_line
			(start 0.67945 0.3048)
			(end 0.120396 0.3048)
			(stroke
				(width 0.1)
				(type default)
			)
			(layer "F.Fab")
		)
		(fp_line
			(start 0.67945 -0.3048)
			(end 0.67945 0.3048)
			(stroke
				(width 0.1)
				(type default)
			)
			(layer "F.Fab")
		)
		(fp_line
			(start 0.12065 -0.2794)
			(end 0.12065 -0.3048)
			(stroke
				(width 0.1)
				(type default)
			)
			(layer "F.Fab")
		)
		(fp_line
			(start 0.12065 -0.3048)
			(end 0.67945 -0.3048)
			(stroke
				(width 0.1)
				(type default)
			)
			(layer "F.Fab")
		)
		(fp_line
			(start 0.120396 0.3048)
			(end 0.120396 0.2794)
			(stroke
				(width 0.1)
				(type default)
			)
			(layer "F.Fab")
		)
		(fp_line
			(start 0.120396 0.2794)
			(end -0.12065 0.2794)
			(stroke
				(width 0.1)
				(type default)
			)
			(layer "F.Fab")
		)
		(fp_line
			(start -0.12065 0.3048)
			(end -0.67945 0.3048)
			(stroke
				(width 0.1)
				(type default)
			)
			(layer "F.Fab")
		)
		(fp_line
			(start -0.12065 0.2794)
			(end -0.12065 0.3048)
			(stroke
				(width 0.1)
				(type default)
			)
			(layer "F.Fab")
		)
		(fp_line
			(start -0.12065 -0.2794)
			(end 0.12065 -0.2794)
			(stroke
				(width 0.1)
				(type default)
			)
			(layer "F.Fab")
		)
		(fp_line
			(start -0.12065 -0.305054)
			(end -0.12065 -0.2794)
			(stroke
				(width 0.1)
				(type default)
			)
			(layer "F.Fab")
		)
		(fp_line
			(start -0.67945 0.3048)
			(end -0.67945 -0.305054)
			(stroke
				(width 0.1)
				(type default)
			)
			(layer "F.Fab")
		)
		(fp_line
			(start -0.67945 -0.305054)
			(end -0.12065 -0.305054)
			(stroke
				(width 0.1)
				(type default)
			)
			(layer "F.Fab")
		)
		(pad "1" smd circle
			(at -0.40005 0 180)
			(size 0 0)
			(layers "F.Cu" "F.Mask" "F.Paste")
			(net "JTAG_SCM_TMS")
		)
		(pad "2" smd circle
			(at 0.40005 0 180)
			(size 0 0)
			(layers "F.Cu" "F.Mask" "F.Paste")
			(net "JTAG_SCM_PLD_TMS")
		)
	)
)
